(kicad_pcb
	(version 20260206)
	(generator "pcbnew")
	(generator_version "10.0")
	(general
		(thickness 1.6)
		(legacy_teardrops no)
	)
	(paper "A4")
	(title_block
		(title "pdpb — Lightning_PDPB_BRD.brd")
		(comment 1 "Lightning (Wiwynn / Facebook NVMe JBOF) / footprints 613-620 of 1140")
	)
	(layers
		(0 "F.Cu" signal "TOP")
		(4 "In1.Cu" signal "L2GND")
		(6 "In2.Cu" signal "L3")
		(8 "In3.Cu" signal "L4VCC")
		(10 "In4.Cu" signal "L5VCC")
		(12 "In5.Cu" signal "L6")
		(14 "In6.Cu" signal "L7GND")
		(2 "B.Cu" signal "BOTTOM")
		(9 "F.Adhes" user "F.Adhesive")
		(11 "B.Adhes" user "B.Adhesive")
		(13 "F.Paste" user "Package Geometry/Pastemask Top")
		(15 "B.Paste" user "Package Geometry/Pastemask Bottom")
		(5 "F.SilkS" user "Ref Des/Silkscreen Top")
		(7 "B.SilkS" user "Ref Des/Silkscreen Bottom")
		(1 "F.Mask" user "Board Geometry/Soldermask Top")
		(3 "B.Mask" user "Board Geometry/Soldermask Bottom")
		(17 "Dwgs.User" user "User.Drawings")
		(19 "Cmts.User" user "User.Comments")
		(21 "Eco1.User" user "User.Eco1")
		(23 "Eco2.User" user "User.Eco2")
		(25 "Edge.Cuts" user "Board Geometry/Outline")
		(27 "Margin" user)
		(31 "F.CrtYd" user "Package Geometry/Place Bound Top")
		(29 "B.CrtYd" user "Package Geometry/Place Bound Bottom")
		(35 "F.Fab" user "Ref Des/Assembly Top")
		(33 "B.Fab" user "Ref Des/Assembly Bottom")
	)
	(footprint ""
		(layer "F.Cu")
		(at 212.852 -498.475 180)
		(property "Reference" "PC1185"
			(at 0 0 180)
			(layer "F.SilkS")
			(hide yes)
			(effects
				(font
					(size 1.27 1.27)
				)
			)
		)
		(property "Value" "SC22U25V6KX-GP-U"
			(at -2.860802 -5.279644 180)
			(unlocked yes)
			(layer "F.Fab")
			(hide yes)
			(effects
				(font
					(size 1.016 1.016)
					(thickness 0.1524)
				)
			)
		)
		(property "Device Type" "C1206-TO0D3H75"
			(at -2.860802 -6.803644 180)
			(unlocked yes)
			(layer "F.Fab")
			(hide yes)
			(effects
				(font
					(size 1.016 1.016)
					(thickness 0.1524)
				)
			)
		)
		(duplicate_pad_numbers_are_jumpers no)
		(fp_line
			(start 1.3081 2.3749)
			(end -1.3081 2.3749)
			(stroke
				(width 0.1524)
				(type default)
			)
			(layer "F.SilkS")
		)
		(fp_line
			(start 1.3081 -2.3749)
			(end 1.3081 2.3749)
			(stroke
				(width 0.1524)
				(type default)
			)
			(layer "F.SilkS")
		)
		(fp_line
			(start -1.3081 2.3749)
			(end -1.3081 -2.3749)
			(stroke
				(width 0.1524)
				(type default)
			)
			(layer "F.SilkS")
		)
		(fp_line
			(start -1.3081 -2.3749)
			(end 1.3081 -2.3749)
			(stroke
				(width 0.1524)
				(type default)
			)
			(layer "F.SilkS")
		)
		(fp_rect
			(start -0.8001 1.6002)
			(end 0.8001 -1.6002)
			(stroke
				(width 0)
				(type default)
			)
			(fill no)
			(layer "F.CrtYd")
		)
		(fp_poly
			(pts
				(xy -1.5621 2.4511) (xy -1.5621 1.6002) (xy 0.8001 1.6002) (xy 0.8001 -1.6002) (xy -0.8001 -1.6002)
				(xy -0.8001 1.5875) (xy -1.5621 1.5875) (xy -1.5621 -2.4511) (xy 1.5621 -2.4511) (xy 1.5621 2.4511)
			)
			(stroke
				(width 0)
				(type default)
			)
			(fill no)
			(layer "F.CrtYd")
		)
		(fp_rect
			(start -1.5621 2.4511)
			(end 1.5621 -2.4511)
			(stroke
				(width 0)
				(type default)
			)
			(fill no)
			(layer "F.Fab")
		)
		(pad "1" smd rect
			(at 0 -1.392936 180)
			(size 2.1082 1.4478)
			(layers "F.Cu" "F.Mask" "F.Paste")
			(net "P12V_SSD0")
		)
		(pad "2" smd rect
			(at 0 1.392936 180)
			(size 2.1082 1.4478)
			(layers "F.Cu" "F.Mask" "F.Paste")
			(net "GND")
		)
	)
	(footprint ""
		(layer "F.Cu")
		(at 227.886768 -454.867264 -90)
		(property "Reference" "R9927"
			(at 0 0 270)
			(layer "F.SilkS")
			(hide yes)
			(effects
				(font
					(size 1.27 1.27)
				)
			)
		)
		(property "Value" "4K7R2J-2-GP"
			(at 0.064008 -3.993896 270)
			(unlocked yes)
			(layer "F.Fab")
			(hide yes)
			(effects
				(font
					(size 1.016 1.016)
					(thickness 0.1524)
				)
			)
		)
		(property "Device Type" "R402H16"
			(at 0.064008 -5.517896 270)
			(unlocked yes)
			(layer "F.Fab")
			(hide yes)
			(effects
				(font
					(size 1.016 1.016)
					(thickness 0.1524)
				)
			)
		)
		(duplicate_pad_numbers_are_jumpers no)
		(fp_line
			(start -0.508 -0.9398)
			(end -0.508 0.9398)
			(stroke
				(width 0.1524)
				(type default)
			)
			(layer "F.SilkS")
		)
		(fp_line
			(start 0.508 -0.9398)
			(end -0.508 -0.9398)
			(stroke
				(width 0.1524)
				(type default)
			)
			(layer "F.SilkS")
		)
		(fp_rect
			(start -0.508 0.9398)
			(end 0.508 -0.9398)
			(stroke
				(width 0)
				(type default)
			)
			(fill no)
			(layer "F.CrtYd")
		)
		(fp_rect
			(start -0.508 0.9398)
			(end 0.508 -0.9398)
			(stroke
				(width 0)
				(type default)
			)
			(fill no)
			(layer "F.Fab")
		)
		(pad "1" smd custom
			(at 0 -0.4445 270)
			(size 0.1397 0.1397)
			(layers "F.Cu" "F.Mask" "F.Paste")
			(net "P3V3")
			(options
				(clearance outline)
				(anchor circle)
			)
			(primitives
				(gr_poly
					(pts
						(arc
							(start -0.1778 -0.2794)
							(mid -0.249642 -0.249642)
							(end -0.2794 -0.1778)
						)
						(arc
							(start -0.2794 0.1778)
							(mid -0.249642 0.249642)
							(end -0.1778 0.2794)
						)
						(arc
							(start 0.1778 0.2794)
							(mid 0.249642 0.249642)
							(end 0.2794 0.1778)
						)
						(arc
							(start 0.2794 -0.1778)
							(mid 0.249642 -0.249642)
							(end 0.1778 -0.2794)
						)
					)
					(width 0)
					(fill yes)
				)
			)
		)
		(pad "2" smd custom
			(at 0 0.4445 270)
			(size 0.1397 0.1397)
			(layers "F.Cu" "F.Mask" "F.Paste")
			(net "ATTN_LED_DR0_MOS_N")
			(options
				(clearance outline)
				(anchor circle)
			)
			(primitives
				(gr_poly
					(pts
						(arc
							(start -0.1778 -0.2794)
							(mid -0.249642 -0.249642)
							(end -0.2794 -0.1778)
						)
						(arc
							(start -0.2794 0.1778)
							(mid -0.249642 0.249642)
							(end -0.1778 0.2794)
						)
						(arc
							(start 0.1778 0.2794)
							(mid 0.249642 0.249642)
							(end 0.2794 0.1778)
						)
						(arc
							(start 0.2794 -0.1778)
							(mid 0.249642 -0.249642)
							(end 0.1778 -0.2794)
						)
					)
					(width 0)
					(fill yes)
				)
			)
		)
	)
	(footprint ""
		(layer "F.Cu")
		(at 225.1075 -245.421658 90)
		(property "Reference" "R9914"
			(at 0 0 90)
			(layer "F.SilkS")
			(hide yes)
			(effects
				(font
					(size 1.27 1.27)
				)
			)
		)
		(property "Value" "47KR2J-2-GP"
			(at 0.064008 -3.993896 90)
			(unlocked yes)
			(layer "F.Fab")
			(hide yes)
			(effects
				(font
					(size 1.016 1.016)
					(thickness 0.1524)
				)
			)
		)
		(property "Device Type" "R402H16"
			(at 0.064008 -5.517896 90)
			(unlocked yes)
			(layer "F.Fab")
			(hide yes)
			(effects
				(font
					(size 1.016 1.016)
					(thickness 0.1524)
				)
			)
		)
		(duplicate_pad_numbers_are_jumpers no)
		(fp_line
			(start 0.508 -0.9398)
			(end -0.508 -0.9398)
			(stroke
				(width 0.1524)
				(type default)
			)
			(layer "F.SilkS")
		)
		(fp_line
			(start -0.508 -0.9398)
			(end -0.508 0.9398)
			(stroke
				(width 0.1524)
				(type default)
			)
			(layer "F.SilkS")
		)
		(fp_rect
			(start -0.508 0.9398)
			(end 0.508 -0.9398)
			(stroke
				(width 0)
				(type default)
			)
			(fill no)
			(layer "F.CrtYd")
		)
		(fp_rect
			(start -0.508 0.9398)
			(end 0.508 -0.9398)
			(stroke
				(width 0)
				(type default)
			)
			(fill no)
			(layer "F.Fab")
		)
		(pad "1" smd custom
			(at 0 -0.4445 90)
			(size 0.1397 0.1397)
			(layers "F.Cu" "F.Mask" "F.Paste")
			(net "P3V3")
			(options
				(clearance outline)
				(anchor circle)
			)
			(primitives
				(gr_poly
					(pts
						(arc
							(start -0.1778 -0.2794)
							(mid -0.249642 -0.249642)
							(end -0.2794 -0.1778)
						)
						(arc
							(start -0.2794 0.1778)
							(mid -0.249642 0.249642)
							(end -0.1778 0.2794)
						)
						(arc
							(start 0.1778 0.2794)
							(mid 0.249642 0.249642)
							(end 0.2794 0.1778)
						)
						(arc
							(start 0.2794 -0.1778)
							(mid 0.249642 -0.249642)
							(end 0.1778 -0.2794)
						)
					)
					(width 0)
					(fill yes)
				)
			)
		)
		(pad "2" smd custom
			(at 0 0.4445 90)
			(size 0.1397 0.1397)
			(layers "F.Cu" "F.Mask" "F.Paste")
			(net "ATTN_LED_DR2_N")
			(options
				(clearance outline)
				(anchor circle)
			)
			(primitives
				(gr_poly
					(pts
						(arc
							(start -0.1778 -0.2794)
							(mid -0.249642 -0.249642)
							(end -0.2794 -0.1778)
						)
						(arc
							(start -0.2794 0.1778)
							(mid -0.249642 0.249642)
							(end -0.1778 0.2794)
						)
						(arc
							(start 0.1778 0.2794)
							(mid 0.249642 0.249642)
							(end 0.2794 0.1778)
						)
						(arc
							(start 0.2794 -0.1778)
							(mid 0.249642 -0.249642)
							(end 0.1778 -0.2794)
						)
					)
					(width 0)
					(fill yes)
				)
			)
		)
	)
	(footprint ""
		(layer "F.Cu")
		(at 24.7904 -311.5056)
		(property "Reference" "PC1222"
			(at 0 0 0)
			(layer "F.SilkS")
			(hide yes)
			(effects
				(font
					(size 1.27 1.27)
				)
			)
		)
		(property "Value" "SCD1U50V3KX-GP"
			(at 0 -2.8194 0)
			(unlocked yes)
			(layer "F.Fab")
			(hide yes)
			(effects
				(font
					(size 1.016 1.016)
					(thickness 0.1524)
				)
			)
		)
		(property "Device Type" "C603H36"
			(at 0 -4.3434 0)
			(unlocked yes)
			(layer "F.Fab")
			(hide yes)
			(effects
				(font
					(size 1.016 1.016)
					(thickness 0.1524)
				)
			)
		)
		(duplicate_pad_numbers_are_jumpers no)
		(fp_line
			(start 0.508 0)
			(end -0.508 0)
			(stroke
				(width 0.2032)
				(type default)
			)
			(layer "F.SilkS")
		)
		(fp_rect
			(start -0.5842 1.3335)
			(end 0.5842 -1.3335)
			(stroke
				(width 0)
				(type default)
			)
			(fill no)
			(layer "F.CrtYd")
		)
		(fp_rect
			(start -0.5842 1.3335)
			(end 0.5842 -1.3335)
			(stroke
				(width 0)
				(type default)
			)
			(fill no)
			(layer "F.Fab")
		)
		(pad "1" smd custom
			(at 0 -0.762)
			(size 0.2159 0.2159)
			(layers "F.Cu" "F.Mask" "F.Paste")
			(net "P12V_SSD11")
			(options
				(clearance outline)
				(anchor circle)
			)
			(primitives
				(gr_poly
					(pts
						(arc
							(start -0.3302 -0.4318)
							(mid -0.402042 -0.402042)
							(end -0.4318 -0.3302)
						)
						(arc
							(start -0.4318 0.3302)
							(mid -0.402042 0.402042)
							(end -0.3302 0.4318)
						)
						(arc
							(start 0.3302 0.4318)
							(mid 0.402042 0.402042)
							(end 0.4318 0.3302)
						)
						(arc
							(start 0.4318 -0.3302)
							(mid 0.402042 -0.402042)
							(end 0.3302 -0.4318)
						)
					)
					(width 0)
					(fill yes)
				)
			)
		)
		(pad "2" smd custom
			(at 0 0.762)
			(size 0.2159 0.2159)
			(layers "F.Cu" "F.Mask" "F.Paste")
			(net "GND")
			(options
				(clearance outline)
				(anchor circle)
			)
			(primitives
				(gr_poly
					(pts
						(arc
							(start -0.3302 -0.4318)
							(mid -0.402042 -0.402042)
							(end -0.4318 -0.3302)
						)
						(arc
							(start -0.4318 0.3302)
							(mid -0.402042 0.402042)
							(end -0.3302 0.4318)
						)
						(arc
							(start 0.3302 0.4318)
							(mid 0.402042 0.402042)
							(end 0.4318 0.3302)
						)
						(arc
							(start 0.4318 -0.3302)
							(mid 0.402042 -0.402042)
							(end 0.3302 -0.4318)
						)
					)
					(width 0)
					(fill yes)
				)
			)
		)
	)
	(footprint ""
		(layer "F.Cu")
		(at 225.425 -431.292 -90)
		(property "Reference" "PC1259"
			(at 0 0 270)
			(layer "F.SilkS")
			(hide yes)
			(effects
				(font
					(size 1.27 1.27)
				)
			)
		)
		(property "Value" "SCD1U25V2KX-2-GP"
			(at 1.1811 -2.7051 270)
			(unlocked yes)
			(layer "F.Fab")
			(hide yes)
			(effects
				(font
					(size 1.016 1.016)
					(thickness 0.1524)
				)
			)
		)
		(property "Device Type" "C402H22"
			(at 1.1811 -4.2291 270)
			(unlocked yes)
			(layer "F.Fab")
			(hide yes)
			(effects
				(font
					(size 1.016 1.016)
					(thickness 0.1524)
				)
			)
		)
		(duplicate_pad_numbers_are_jumpers no)
		(fp_rect
			(start -0.4318 0.9525)
			(end 0.4318 -0.9525)
			(stroke
				(width 0)
				(type default)
			)
			(fill no)
			(layer "F.CrtYd")
		)
		(fp_rect
			(start -0.4318 0.9525)
			(end 0.4318 -0.9525)
			(stroke
				(width 0)
				(type default)
			)
			(fill no)
			(layer "F.Fab")
		)
		(pad "1" smd custom
			(at 0 -0.4445 270)
			(size 0.1524 0.1524)
			(layers "F.Cu" "F.Mask" "F.Paste")
			(net "P3V3_VIN")
			(options
				(clearance outline)
				(anchor circle)
			)
			(primitives
				(gr_poly
					(pts
						(arc
							(start 0.3048 -0.2032)
							(mid 0.275042 -0.275042)
							(end 0.2032 -0.3048)
						)
						(arc
							(start -0.2032 -0.3048)
							(mid -0.275042 -0.275042)
							(end -0.3048 -0.2032)
						)
						(arc
							(start -0.3048 0.2032)
							(mid -0.275042 0.275042)
							(end -0.2032 0.3048)
						)
						(arc
							(start 0.2032 0.3048)
							(mid 0.275042 0.275042)
							(end 0.3048 0.2032)
						)
					)
					(width 0)
					(fill yes)
				)
			)
		)
		(pad "2" smd custom
			(at 0 0.4445 270)
			(size 0.1524 0.1524)
			(layers "F.Cu" "F.Mask" "F.Paste")
			(net "GND")
			(options
				(clearance outline)
				(anchor circle)
			)
			(primitives
				(gr_poly
					(pts
						(arc
							(start 0.3048 -0.2032)
							(mid 0.275042 -0.275042)
							(end 0.2032 -0.3048)
						)
						(arc
							(start -0.2032 -0.3048)
							(mid -0.275042 -0.275042)
							(end -0.3048 -0.2032)
						)
						(arc
							(start -0.3048 0.2032)
							(mid -0.275042 0.275042)
							(end -0.2032 0.3048)
						)
						(arc
							(start 0.2032 0.3048)
							(mid 0.275042 0.275042)
							(end 0.3048 0.2032)
						)
					)
					(width 0)
					(fill yes)
				)
			)
		)
	)
	(footprint ""
		(layer "F.Cu")
		(at 227.35159 -348.323154 90)
		(property "Reference" "R9930"
			(at 0 0 90)
			(layer "F.SilkS")
			(hide yes)
			(effects
				(font
					(size 1.27 1.27)
				)
			)
		)
		(property "Value" "4K7R2J-2-GP"
			(at 0.064008 -3.993896 90)
			(unlocked yes)
			(layer "F.Fab")
			(hide yes)
			(effects
				(font
					(size 1.016 1.016)
					(thickness 0.1524)
				)
			)
		)
		(property "Device Type" "R402H16"
			(at 0.064008 -5.517896 90)
			(unlocked yes)
			(layer "F.Fab")
			(hide yes)
			(effects
				(font
					(size 1.016 1.016)
					(thickness 0.1524)
				)
			)
		)
		(duplicate_pad_numbers_are_jumpers no)
		(fp_line
			(start 0.508 -0.9398)
			(end -0.508 -0.9398)
			(stroke
				(width 0.1524)
				(type default)
			)
			(layer "F.SilkS")
		)
		(fp_line
			(start -0.508 -0.9398)
			(end -0.508 0.9398)
			(stroke
				(width 0.1524)
				(type default)
			)
			(layer "F.SilkS")
		)
		(fp_rect
			(start -0.508 0.9398)
			(end 0.508 -0.9398)
			(stroke
				(width 0)
				(type default)
			)
			(fill no)
			(layer "F.CrtYd")
		)
		(fp_rect
			(start -0.508 0.9398)
			(end 0.508 -0.9398)
			(stroke
				(width 0)
				(type default)
			)
			(fill no)
			(layer "F.Fab")
		)
		(pad "1" smd custom
			(at 0 -0.4445 90)
			(size 0.1397 0.1397)
			(layers "F.Cu" "F.Mask" "F.Paste")
			(net "P3V3")
			(options
				(clearance outline)
				(anchor circle)
			)
			(primitives
				(gr_poly
					(pts
						(arc
							(start -0.1778 -0.2794)
							(mid -0.249642 -0.249642)
							(end -0.2794 -0.1778)
						)
						(arc
							(start -0.2794 0.1778)
							(mid -0.249642 0.249642)
							(end -0.1778 0.2794)
						)
						(arc
							(start 0.1778 0.2794)
							(mid 0.249642 0.249642)
							(end 0.2794 0.1778)
						)
						(arc
							(start 0.2794 -0.1778)
							(mid 0.249642 -0.249642)
							(end 0.1778 -0.2794)
						)
					)
					(width 0)
					(fill yes)
				)
			)
		)
		(pad "2" smd custom
			(at 0 0.4445 90)
			(size 0.1397 0.1397)
			(layers "F.Cu" "F.Mask" "F.Paste")
			(net "SSD_ACT_DR1_MOS_N")
			(options
				(clearance outline)
				(anchor circle)
			)
			(primitives
				(gr_poly
					(pts
						(arc
							(start -0.1778 -0.2794)
							(mid -0.249642 -0.249642)
							(end -0.2794 -0.1778)
						)
						(arc
							(start -0.2794 0.1778)
							(mid -0.249642 0.249642)
							(end -0.1778 0.2794)
						)
						(arc
							(start 0.1778 0.2794)
							(mid 0.249642 0.249642)
							(end 0.2794 0.1778)
						)
						(arc
							(start 0.2794 -0.1778)
							(mid 0.249642 -0.249642)
							(end 0.1778 -0.2794)
						)
					)
					(width 0)
					(fill yes)
				)
			)
		)
	)
	(footprint ""
		(layer "F.Cu")
		(at 222.0214 -189.23)
		(property "Reference" "PC1228"
			(at 0 0 0)
			(layer "F.SilkS")
			(hide yes)
			(effects
				(font
					(size 1.27 1.27)
				)
			)
		)
		(property "Value" "SCD01U50V2KX-1GP"
			(at 1.1811 -2.7051 0)
			(unlocked yes)
			(layer "F.Fab")
			(hide yes)
			(effects
				(font
					(size 1.016 1.016)
					(thickness 0.1524)
				)
			)
		)
		(property "Device Type" "C402H22"
			(at 1.1811 -4.2291 0)
			(unlocked yes)
			(layer "F.Fab")
			(hide yes)
			(effects
				(font
					(size 1.016 1.016)
					(thickness 0.1524)
				)
			)
		)
		(duplicate_pad_numbers_are_jumpers no)
		(fp_rect
			(start -0.4318 0.9525)
			(end 0.4318 -0.9525)
			(stroke
				(width 0)
				(type default)
			)
			(fill no)
			(layer "F.CrtYd")
		)
		(fp_rect
			(start -0.4318 0.9525)
			(end 0.4318 -0.9525)
			(stroke
				(width 0)
				(type default)
			)
			(fill no)
			(layer "F.Fab")
		)
		(pad "1" smd custom
			(at 0 -0.4445)
			(size 0.1524 0.1524)
			(layers "F.Cu" "F.Mask" "F.Paste")
			(net "P12V_SSD3")
			(options
				(clearance outline)
				(anchor circle)
			)
			(primitives
				(gr_poly
					(pts
						(arc
							(start 0.3048 -0.2032)
							(mid 0.275042 -0.275042)
							(end 0.2032 -0.3048)
						)
						(arc
							(start -0.2032 -0.3048)
							(mid -0.275042 -0.275042)
							(end -0.3048 -0.2032)
						)
						(arc
							(start -0.3048 0.2032)
							(mid -0.275042 0.275042)
							(end -0.2032 0.3048)
						)
						(arc
							(start 0.2032 0.3048)
							(mid 0.275042 0.275042)
							(end 0.3048 0.2032)
						)
					)
					(width 0)
					(fill yes)
				)
			)
		)
		(pad "2" smd custom
			(at 0 0.4445)
			(size 0.1524 0.1524)
			(layers "F.Cu" "F.Mask" "F.Paste")
			(net "GND")
			(options
				(clearance outline)
				(anchor circle)
			)
			(primitives
				(gr_poly
					(pts
						(arc
							(start 0.3048 -0.2032)
							(mid 0.275042 -0.275042)
							(end 0.2032 -0.3048)
						)
						(arc
							(start -0.2032 -0.3048)
							(mid -0.275042 -0.275042)
							(end -0.3048 -0.2032)
						)
						(arc
							(start -0.3048 0.2032)
							(mid -0.275042 0.275042)
							(end -0.2032 0.3048)
						)
						(arc
							(start 0.2032 0.3048)
							(mid 0.275042 0.275042)
							(end 0.3048 0.2032)
						)
					)
					(width 0)
					(fill yes)
				)
			)
		)
	)
	(footprint ""
		(layer "F.Cu")
		(at 98.806 -222.885 -90)
		(property "Reference" "C9357"
			(at 0 0 270)
			(layer "F.SilkS")
			(hide yes)
			(effects
				(font
					(size 1.27 1.27)
				)
			)
		)
		(property "Value" "SC1KP50V2KX-1GP"
			(at 1.1811 -2.7051 270)
			(unlocked yes)
			(layer "F.Fab")
			(hide yes)
			(effects
				(font
					(size 1.016 1.016)
					(thickness 0.1524)
				)
			)
		)
		(property "Device Type" "C402H22"
			(at 1.1811 -4.2291 270)
			(unlocked yes)
			(layer "F.Fab")
			(hide yes)
			(effects
				(font
					(size 1.016 1.016)
					(thickness 0.1524)
				)
			)
		)
		(duplicate_pad_numbers_are_jumpers no)
		(fp_rect
			(start -0.4318 0.9525)
			(end 0.4318 -0.9525)
			(stroke
				(width 0)
				(type default)
			)
			(fill no)
			(layer "F.CrtYd")
		)
		(fp_rect
			(start -0.4318 0.9525)
			(end 0.4318 -0.9525)
			(stroke
				(width 0)
				(type default)
			)
			(fill no)
			(layer "F.Fab")
		)
		(pad "1" smd custom
			(at 0 -0.4445 270)
			(size 0.1524 0.1524)
			(layers "F.Cu" "F.Mask" "F.Paste")
			(net "SSD_PRSNT7")
			(options
				(clearance outline)
				(anchor circle)
			)
			(primitives
				(gr_poly
					(pts
						(arc
							(start 0.3048 -0.2032)
							(mid 0.275042 -0.275042)
							(end 0.2032 -0.3048)
						)
						(arc
							(start -0.2032 -0.3048)
							(mid -0.275042 -0.275042)
							(end -0.3048 -0.2032)
						)
						(arc
							(start -0.3048 0.2032)
							(mid -0.275042 0.275042)
							(end -0.2032 0.3048)
						)
						(arc
							(start 0.2032 0.3048)
							(mid 0.275042 0.275042)
							(end 0.3048 0.2032)
						)
					)
					(width 0)
					(fill yes)
				)
			)
		)
		(pad "2" smd custom
			(at 0 0.4445 270)
			(size 0.1524 0.1524)
			(layers "F.Cu" "F.Mask" "F.Paste")
			(net "GND")
			(options
				(clearance outline)
				(anchor circle)
			)
			(primitives
				(gr_poly
					(pts
						(arc
							(start 0.3048 -0.2032)
							(mid 0.275042 -0.275042)
							(end 0.2032 -0.3048)
						)
						(arc
							(start -0.2032 -0.3048)
							(mid -0.275042 -0.275042)
							(end -0.3048 -0.2032)
						)
						(arc
							(start -0.3048 0.2032)
							(mid -0.275042 0.275042)
							(end -0.2032 0.3048)
						)
						(arc
							(start 0.2032 0.3048)
							(mid 0.275042 0.275042)
							(end 0.3048 0.2032)
						)
					)
					(width 0)
					(fill yes)
				)
			)
		)
	)
)
